# T6G (Grand Teton) — schematic netlist excerpt (pin names and nets, part order shuffled) for the footprints in the layout excerpt that follows; sources: Cadence DE-HDL packaged netlist, KiCad conversion of 04192023_DAF0TMB3IC0_F0TG_MB_C_brd_V02_OCP.brd

C893  Q_CAP_DIFFBUS  DIFF BUS_0.22UF 6.3V 20% X6S  pkg C0201  page 64 : \1\ = P5E_CPU0_P3_TX_C_DP<4> ; \2\ = P5E_CPU0_P3_TX_DP<4>
C5003  Q_CAP  1000PF 50V 5% X7R  pkg 0402  page 210 : A = GND ; B = PWRGD_PVDDCR_CPU0_P1
R4194  Q_RES  1K 1% EMPTY  pkg 0402LF  page 235 : A = P3V3_AUX ; B = U272_2_ADD1

(kicad_pcb
	(version 20260206)
	(generator "pcbnew")
	(generator_version "10.0")
	(general
		(thickness 1.6)
		(legacy_teardrops no)
	)
	(paper "A4")
	(title_block
		(title "04192023_DAF0TMB3IC0_F0TG_MB_C_brd_V02_OCP.brd")
		(comment 1 "Grand Teton / footprints 2464-2466 of 8354")
	)
	(layers
		(0 "F.Cu" signal "TOP")
		(4 "In1.Cu" signal "GND")
		(6 "In2.Cu" signal "IN1")
		(8 "In3.Cu" signal "GND1")
		(10 "In4.Cu" signal "IN2")
		(12 "In5.Cu" signal "GND2")
		(14 "In6.Cu" signal "IN3")
		(16 "In7.Cu" signal "GND3")
		(18 "In8.Cu" signal "VCC")
		(20 "In9.Cu" signal "VCC1")
		(22 "In10.Cu" signal "GND4")
		(24 "In11.Cu" signal "IN4")
		(26 "In12.Cu" signal "GND5")
		(28 "In13.Cu" signal "IN5")
		(30 "In14.Cu" signal "GND6")
		(32 "In15.Cu" signal "IN6")
		(34 "In16.Cu" signal "GND7")
		(2 "B.Cu" signal "BOTTOM")
		(9 "F.Adhes" user "F.Adhesive")
		(11 "B.Adhes" user "B.Adhesive")
		(13 "F.Paste" user "Package Geometry/Pastemask Top")
		(15 "B.Paste" user "Package Geometry/Pastemask Bottom")
		(5 "F.SilkS" user "Ref Des/Silkscreen Top")
		(7 "B.SilkS" user "Ref Des/Silkscreen Bottom")
		(1 "F.Mask" user "Board Geometry/Soldermask Top")
		(3 "B.Mask" user "Board Geometry/Soldermask Bottom")
		(17 "Dwgs.User" user "User.Drawings")
		(19 "Cmts.User" user "User.Comments")
		(21 "Eco1.User" user "User.Eco1")
		(23 "Eco2.User" user "User.Eco2")
		(25 "Edge.Cuts" user "Board Geometry/Outline")
		(27 "Margin" user)
		(31 "F.CrtYd" user "Package Geometry/Place Bound Top")
		(29 "B.CrtYd" user "Package Geometry/Place Bound Bottom")
		(35 "F.Fab" user "Ref Des/Assembly Top")
		(33 "B.Fab" user "Ref Des/Assembly Bottom")
	)
	(footprint ""
		(layer "F.Cu")
		(at 99.650296 -425.82973 -90)
		(property "Reference" "R4194"
			(at 0 0 270)
			(layer "F.SilkS")
			(hide yes)
			(effects
				(font
					(size 1.27 1.27)
				)
			)
		)
		(property "Value" ""
			(at 0 0 270)
			(layer "F.Fab")
			(effects
				(font
					(size 1.27 1.27)
				)
			)
		)
		(duplicate_pad_numbers_are_jumpers no)
		(fp_line
			(start -0.7874 0.4064)
			(end -0.7874 -0.4064)
			(stroke
				(width 0.1524)
				(type default)
			)
			(layer "F.SilkS")
		)
		(fp_line
			(start 0.7874 0.4064)
			(end -0.7874 0.4064)
			(stroke
				(width 0.1524)
				(type default)
			)
			(layer "F.SilkS")
		)
		(fp_line
			(start -0.7874 -0.4064)
			(end 0.7874 -0.4064)
			(stroke
				(width 0.1524)
				(type default)
			)
			(layer "F.SilkS")
		)
		(fp_line
			(start 0.7874 -0.4064)
			(end 0.7874 0.4064)
			(stroke
				(width 0.1524)
				(type default)
			)
			(layer "F.SilkS")
		)
		(fp_line
			(start -0.67945 0.3048)
			(end -0.67945 -0.305054)
			(stroke
				(width 0.1)
				(type default)
			)
			(layer "F.Fab")
		)
		(fp_line
			(start -0.12065 0.3048)
			(end -0.67945 0.3048)
			(stroke
				(width 0.1)
				(type default)
			)
			(layer "F.Fab")
		)
		(fp_line
			(start 0.120396 0.3048)
			(end 0.120396 0.2794)
			(stroke
				(width 0.1)
				(type default)
			)
			(layer "F.Fab")
		)
		(fp_line
			(start 0.67945 0.3048)
			(end 0.120396 0.3048)
			(stroke
				(width 0.1)
				(type default)
			)
			(layer "F.Fab")
		)
		(fp_line
			(start -0.12065 0.2794)
			(end -0.12065 0.3048)
			(stroke
				(width 0.1)
				(type default)
			)
			(layer "F.Fab")
		)
		(fp_line
			(start 0.120396 0.2794)
			(end -0.12065 0.2794)
			(stroke
				(width 0.1)
				(type default)
			)
			(layer "F.Fab")
		)
		(fp_line
			(start -0.12065 -0.2794)
			(end 0.12065 -0.2794)
			(stroke
				(width 0.1)
				(type default)
			)
			(layer "F.Fab")
		)
		(fp_line
			(start 0.12065 -0.2794)
			(end 0.12065 -0.3048)
			(stroke
				(width 0.1)
				(type default)
			)
			(layer "F.Fab")
		)
		(fp_line
			(start 0.12065 -0.3048)
			(end 0.67945 -0.3048)
			(stroke
				(width 0.1)
				(type default)
			)
			(layer "F.Fab")
		)
		(fp_line
			(start 0.67945 -0.3048)
			(end 0.67945 0.3048)
			(stroke
				(width 0.1)
				(type default)
			)
			(layer "F.Fab")
		)
		(fp_line
			(start -0.67945 -0.305054)
			(end -0.12065 -0.305054)
			(stroke
				(width 0.1)
				(type default)
			)
			(layer "F.Fab")
		)
		(fp_line
			(start -0.12065 -0.305054)
			(end -0.12065 -0.2794)
			(stroke
				(width 0.1)
				(type default)
			)
			(layer "F.Fab")
		)
		(pad "1" smd circle
			(at -0.40005 0 270)
			(size 0 0)
			(layers "F.Cu" "F.Mask" "F.Paste")
			(net "P3V3_AUX")
		)
		(pad "2" smd circle
			(at 0.40005 0 270)
			(size 0 0)
			(layers "F.Cu" "F.Mask" "F.Paste")
			(net "U272_2_ADD1")
		)
	)
	(footprint ""
		(layer "F.Cu")
		(at 371.195092 -383.88163 -90)
		(property "Reference" "C893"
			(at 0 0 270)
			(layer "F.SilkS")
			(hide yes)
			(effects
				(font
					(size 1.27 1.27)
				)
			)
		)
		(property "Value" ""
			(at 0 0 270)
			(layer "F.Fab")
			(effects
				(font
					(size 1.27 1.27)
				)
			)
		)
		(duplicate_pad_numbers_are_jumpers no)
		(fp_line
			(start -0.299974 0.150114)
			(end -0.299974 -0.150114)
			(stroke
				(width 0.1)
				(type default)
			)
			(layer "F.Fab")
		)
		(fp_line
			(start 0.299974 0.150114)
			(end -0.299974 0.150114)
			(stroke
				(width 0.1)
				(type default)
			)
			(layer "F.Fab")
		)
		(fp_line
			(start -0.299974 -0.150114)
			(end 0.299974 -0.150114)
			(stroke
				(width 0.1)
				(type default)
			)
			(layer "F.Fab")
		)
		(fp_line
			(start 0.299974 -0.150114)
			(end 0.299974 0.150114)
			(stroke
				(width 0.1)
				(type default)
			)
			(layer "F.Fab")
		)
		(pad "1" smd rect
			(at -0.2667 0 270)
			(size 0.3048 0.381)
			(layers "F.Cu" "F.Mask" "F.Paste")
			(net "P5E_CPU0_P3_TX_C_DP<4>")
		)
		(pad "2" smd rect
			(at 0.2667 0 270)
			(size 0.3048 0.381)
			(layers "F.Cu" "F.Mask" "F.Paste")
			(net "P5E_CPU0_P3_TX_DP<4>")
		)
	)
	(footprint ""
		(layer "F.Cu")
		(at 90.832178 -139.80541)
		(property "Reference" "C5003"
			(at 0 0 0)
			(layer "F.SilkS")
			(hide yes)
			(effects
				(font
					(size 1.27 1.27)
				)
			)
		)
		(property "Value" ""
			(at 0 0 0)
			(layer "F.Fab")
			(effects
				(font
					(size 1.27 1.27)
				)
			)
		)
		(duplicate_pad_numbers_are_jumpers no)
		(fp_line
			(start -0.7874 -0.4064)
			(end 0.7874 -0.4064)
			(stroke
				(width 0.1524)
				(type default)
			)
			(layer "F.SilkS")
		)
		(fp_line
			(start -0.7874 0.4064)
			(end -0.7874 -0.4064)
			(stroke
				(width 0.1524)
				(type default)
			)
			(layer "F.SilkS")
		)
		(fp_line
			(start 0.7874 -0.4064)
			(end 0.7874 0.4064)
			(stroke
				(width 0.1524)
				(type default)
			)
			(layer "F.SilkS")
		)
		(fp_line
			(start 0.7874 0.4064)
			(end -0.7874 0.4064)
			(stroke
				(width 0.1524)
				(type default)
			)
			(layer "F.SilkS")
		)
		(fp_line
			(start -0.67945 -0.305054)
			(end -0.12065 -0.305054)
			(stroke
				(width 0.1)
				(type default)
			)
			(layer "F.Fab")
		)
		(fp_line
			(start -0.67945 0.3048)
			(end -0.67945 -0.305054)
			(stroke
				(width 0.1)
				(type default)
			)
			(layer "F.Fab")
		)
		(fp_line
			(start -0.12065 -0.305054)
			(end -0.12065 -0.2794)
			(stroke
				(width 0.1)
				(type default)
			)
			(layer "F.Fab")
		)
		(fp_line
			(start -0.12065 -0.2794)
			(end 0.12065 -0.2794)
			(stroke
				(width 0.1)
				(type default)
			)
			(layer "F.Fab")
		)
		(fp_line
			(start -0.12065 0.2794)
			(end -0.12065 0.3048)
			(stroke
				(width 0.1)
				(type default)
			)
			(layer "F.Fab")
		)
		(fp_line
			(start -0.12065 0.3048)
			(end -0.67945 0.3048)
			(stroke
				(width 0.1)
				(type default)
			)
			(layer "F.Fab")
		)
		(fp_line
			(start 0.120396 0.2794)
			(end -0.12065 0.2794)
			(stroke
				(width 0.1)
				(type default)
			)
			(layer "F.Fab")
		)
		(fp_line
			(start 0.120396 0.3048)
			(end 0.120396 0.2794)
			(stroke
				(width 0.1)
				(type default)
			)
			(layer "F.Fab")
		)
		(fp_line
			(start 0.12065 -0.3048)
			(end 0.67945 -0.3048)
			(stroke
				(width 0.1)
				(type default)
			)
			(layer "F.Fab")
		)
		(fp_line
			(start 0.12065 -0.2794)
			(end 0.12065 -0.3048)
			(stroke
				(width 0.1)
				(type default)
			)
			(layer "F.Fab")
		)
		(fp_line
			(start 0.67945 -0.3048)
			(end 0.67945 0.3048)
			(stroke
				(width 0.1)
				(type default)
			)
			(layer "F.Fab")
		)
		(fp_line
			(start 0.67945 0.3048)
			(end 0.120396 0.3048)
			(stroke
				(width 0.1)
				(type default)
			)
			(layer "F.Fab")
		)
		(pad "1" smd circle
			(at -0.40005 0)
			(size 0 0)
			(layers "F.Cu" "F.Mask" "F.Paste")
			(net "GND")
		)
		(pad "2" smd circle
			(at 0.40005 0)
			(size 0 0)
			(layers "F.Cu" "F.Mask" "F.Paste")
			(net "PWRGD_PVDDCR_CPU0_P1")
		)
	)
)
